FILE_TYPE = MACRO_DRAWING;
SET COLOR_WIRE YELLOW;
SET COLOR_PROP ORANGE;
SET COLOR_DOT WHITE;
SET COLOR_ARC YELLOW;
SET COLOR_BODY GREEN;
SET COLOR_NOTE PURPLE;
SET PROP_DISPLAY VALUE;
SET PAGE_NUMBER P145;
FORCEADD QUANTA_TITLE_BLOCK_C..1
(-3100 25);
FORCEPROP 1 LAST CUSTOM_TXT_CDS <NAME_2>
J 0
(-6275 75);
FORCEPROP 1 LAST CUSTOM_TXT_CDS <NAME_1>
J 0
(-6275 200);
FORCEPROP 1 LAST CUSTOM_TXT_CDS <Q_NUMBER>
J 0
(-4503 128);
DISPLAY 1.212766 (-4503 128);
FORCEPROP 1 LAST CUSTOM_TXT_CDS <Q_PROJ>
J 0
(-5482 127);
DISPLAY 1.212766 (-5482 127);
FORCEPROP 1 LAST CUSTOM_TXT_CDS <Q_REV>
J 0
(-3284 128);
DISPLAY 1.212766 (-3284 128);
FORCEPROP 1 LAST CUSTOM_TXT_CDS <CON_LAST_MODIFIED>
J 0
(-4985 40);
DISPLAY 0.978723 (-4985 40);
FORCEPROP 1 LAST CUSTOM_TXT_CDS <CON_PAGE_NUM> OF <CON_TOTAL_PAGES>
J 0
(-3546 43);
DISPLAY 0.978723 (-3546 43);
FORCEPROP 1 LAST Q_TITLE Blank
J 0
(-12375 100);
DISPLAY 2.446809 (-12375 100);
PAINT GREEN (-12375 100);
FORCEPROP 2 LAST PAGE_BORDER TRUE
J 0
(-10990 5275);
DISPLAY 0.638298 (-10990 5275);
PAINT PINK (-10990 5275);
DISPLAY INVISIBLE (-10990 5275);
FORCEPROP 1 LAST CDS_LMAN_SYM_OUTLINE -9475,6775,100,-125
J 0
(-3100 25);
DISPLAY 0.468085 (-3100 25);
PAINT GREEN (-3100 25);
DISPLAY INVISIBLE (-3100 25);
FORCEPROP 2 LAST CDS_LIB pure_quanta
J 0
(-3100 25);
DISPLAY INVISIBLE (-3100 25);
FORCEPROP 2 LAST CDS_XR_PAGE_TITLE CR-168 : @T6G_MB_LIB.T6G(SCH_1):PAGE168
J 0
(-10990 5275);
DISPLAY 0.638298 (-10990 5275);
PAINT PINK (-10990 5275);
DISPLAY INVISIBLE (-10990 5275);
FORCEPROP 2 LAST CUSTOM_TXT_CDS <XR_PAGE_TITLE>
J 0
(-10990 5275);
DISPLAY 0.638298 (-10990 5275);
PAINT PINK (-10990 5275);
DISPLAY INVISIBLE (-10990 5275);
FORCEPROP 1 LAST COMMENT_BODY TRUE
J 0
(-3088 12);
DISPLAY 0.978723 (-3088 12);
PAINT GREEN (-3088 12);
DISPLAY INVISIBLE (-3088 12);
FORCEPROP 1 LAST Q_DEPT BU9
J 1
(-6863 74);
DISPLAY 1.957447 (-6863 74);
PAINT GREEN (-6863 74);
DISPLAY INVISIBLE (-6863 74);
FORCEPROP 0 LAST CDS_CON_LAST_MODIFIED Thu Aug 24 10:14:50 2023
J 0
(-4985 40);
DISPLAY INVISIBLE (-4985 40);
QUIT
